# TIMECARD (Time Appliance Project (Time Card)) — schematic netlist excerpt (pin names and nets, part order shuffled) for the footprints in the layout excerpt that follows; sources: Cadence DE-HDL packaged netlist, KiCad conversion of R4006-B0001-02_R01.brd

TP180  TP_PIONT  pkg TP010CT020B030_PTH  page 25 : \1\ = IO_L20N_16
R439  RESISTOR  10KOHM 1%  pkg SMC_0402R_H016  page 13 : \1\ = FPGA_IN_MAC_PPS_OUTP ; \2\ = XP2R5V_FPGA
TP22  TP_PIONT  pkg TP010CT020B030_PTH  page 25 : \1\ = FPGA_IN_LM75B_INT3_N
SP29  SOLDER_PREFORM  pkg 0201_SOLDER_PREFORM_4MIL  page 34 : \1\ = NC ; \2\ = NC

(kicad_pcb
	(version 20260206)
	(generator "pcbnew")
	(generator_version "10.0")
	(general
		(thickness 1.6)
		(legacy_teardrops no)
	)
	(paper "A4")
	(title_block
		(title "timecard-production-celestica-r4006 — R4006-B0001-02_R01.brd")
		(comment 1 "Time Appliance Project (Time Card) / footprints 486-489 of 1113")
	)
	(layers
		(0 "F.Cu" signal "TOP")
		(4 "In1.Cu" signal "L02_GND1")
		(6 "In2.Cu" signal "L03_SIG1")
		(8 "In3.Cu" signal "L04_GND2")
		(10 "In4.Cu" signal "L05_VCC1")
		(12 "In5.Cu" signal "L06_VCC2")
		(14 "In6.Cu" signal "L07_GND3")
		(16 "In7.Cu" signal "L08_SIG2")
		(18 "In8.Cu" signal "L09_GND4")
		(2 "B.Cu" signal "BOTTOM")
		(9 "F.Adhes" user "F.Adhesive")
		(11 "B.Adhes" user "B.Adhesive")
		(13 "F.Paste" user "Package Geometry/Pastemask Top")
		(15 "B.Paste" user "Package Geometry/Pastemask Bottom")
		(5 "F.SilkS" user "Ref Des/Silkscreen Top")
		(7 "B.SilkS" user "Ref Des/Silkscreen Bottom")
		(1 "F.Mask" user "Board Geometry/Soldermask Top")
		(3 "B.Mask" user "Board Geometry/Soldermask Bottom")
		(17 "Dwgs.User" user "User.Drawings")
		(19 "Cmts.User" user "User.Comments")
		(21 "Eco1.User" user "User.Eco1")
		(23 "Eco2.User" user "User.Eco2")
		(25 "Edge.Cuts" user "Board Geometry/Outline")
		(27 "Margin" user)
		(31 "F.CrtYd" user "Package Geometry/Place Bound Top")
		(29 "B.CrtYd" user "Package Geometry/Place Bound Bottom")
		(35 "F.Fab" user "Ref Des/Assembly Top")
		(33 "B.Fab" user "Ref Des/Assembly Bottom")
	)
	(footprint ""
		(layer "F.Cu")
		(at 115.062 -29.464 -90)
		(property "Reference" "R439"
			(at 2.794 -1.18237 90)
			(unlocked yes)
			(layer "F.SilkS")
			(effects
				(font
					(size 0.7874 0.5842)
					(thickness 0.1524)
				)
			)
		)
		(property "Value" "VAL*"
			(at 0.02032 2.13233 270)
			(unlocked yes)
			(layer "F.Fab")
			(hide yes)
			(effects
				(font
					(size 0.7874 0.5842)
					(thickness 0.1524)
				)
			)
		)
		(property "Tolerance" "TOL*"
			(at 0.044704 3.05435 270)
			(unlocked yes)
			(layer "Cmts.User")
			(hide yes)
			(effects
				(font
					(size 0.7874 0.5842)
					(thickness 0.1524)
				)
			)
		)
		(property "User Part Number" "PARTNUM*"
			(at 0.02032 4.024884 270)
			(unlocked yes)
			(layer "Cmts.User")
			(hide yes)
			(effects
				(font
					(size 0.7874 0.5842)
					(thickness 0.1524)
				)
			)
		)
		(property "Device Type" "RESISTOR-G155-11002-01,10KOHM,A"
			(at 0.008382 1.210564 270)
			(unlocked yes)
			(layer "F.Fab")
			(hide yes)
			(effects
				(font
					(size 0.7874 0.5842)
					(thickness 0.1524)
				)
			)
		)
		(duplicate_pad_numbers_are_jumpers no)
		(fp_line
			(start -1.143 0.5588)
			(end 1.143 0.5588)
			(stroke
				(width 0.1)
				(type default)
			)
			(layer "F.SilkS")
		)
		(fp_line
			(start 1.143 0.5588)
			(end 1.143 -0.5588)
			(stroke
				(width 0.1)
				(type default)
			)
			(layer "F.SilkS")
		)
		(fp_line
			(start -1.143 -0.5588)
			(end -1.143 0.5588)
			(stroke
				(width 0.1)
				(type default)
			)
			(layer "F.SilkS")
		)
		(fp_line
			(start 1.143 -0.5588)
			(end -1.143 -0.5588)
			(stroke
				(width 0.1)
				(type default)
			)
			(layer "F.SilkS")
		)
		(fp_poly
			(pts
				(xy -1.143 0.5588) (xy 1.143 0.5588) (xy 1.143 -0.5588) (xy -1.143 -0.5588)
			)
			(stroke
				(width 0)
				(type default)
			)
			(fill no)
			(layer "F.CrtYd")
		)
		(fp_line
			(start -0.508 0.3048)
			(end 0.508 0.3048)
			(stroke
				(width 0.1)
				(type default)
			)
			(layer "F.Fab")
		)
		(fp_line
			(start 0.508 0.3048)
			(end 0.508 -0.3048)
			(stroke
				(width 0.1)
				(type default)
			)
			(layer "F.Fab")
		)
		(fp_line
			(start -0.508 -0.3048)
			(end -0.508 0.3048)
			(stroke
				(width 0.1)
				(type default)
			)
			(layer "F.Fab")
		)
		(fp_line
			(start 0.508 -0.3048)
			(end -0.508 -0.3048)
			(stroke
				(width 0.1)
				(type default)
			)
			(layer "F.Fab")
		)
		(pad "1" smd rect
			(at -0.5334 0 270)
			(size 0.7112 0.6096)
			(layers "F.Cu" "F.Mask" "F.Paste")
			(net "FPGA_IN_MAC_PPS_OUTP")
		)
		(pad "2" smd rect
			(at 0.5334 0 270)
			(size 0.7112 0.6096)
			(layers "F.Cu" "F.Mask" "F.Paste")
			(net "XP2R5V_FPGA")
		)
		(zone
			(layer "F.Cu")
			(hatch none 0.5)
			(connect_pads
				(clearance 0)
			)
			(min_thickness 0.25)
			(keepout
				(tracks allowed)
				(vias not_allowed)
				(pads allowed)
				(copperpour not_allowed)
				(footprints allowed)
			)
			(placement
				(enabled no)
				(sheetname "")
			)
			(fill
				(thermal_gap 0.5)
				(thermal_bridge_width 0.5)
				(island_removal_mode 0)
			)
			(polygon
				(pts
					(xy 114.7572 -29.5402) (xy 114.7572 -29.3878) (xy 115.3668 -29.3878) (xy 115.3668 -29.5402)
				)
			)
		)
		(zone
			(layer "F.Cu")
			(hatch none 0.5)
			(connect_pads
				(clearance 0)
			)
			(min_thickness 0.25)
			(keepout
				(tracks not_allowed)
				(vias allowed)
				(pads allowed)
				(copperpour not_allowed)
				(footprints allowed)
			)
			(placement
				(enabled no)
				(sheetname "")
			)
			(fill
				(thermal_gap 0.5)
				(thermal_bridge_width 0.5)
				(island_removal_mode 0)
			)
			(polygon
				(pts
					(xy 114.7572 -29.5402) (xy 114.7572 -29.3878) (xy 115.3668 -29.3878) (xy 115.3668 -29.5402)
				)
			)
		)
	)
	(footprint ""
		(layer "F.Cu")
		(at 60.452 -123.952)
		(property "Reference" "SP29"
			(at 0 0 0)
			(layer "F.SilkS")
			(hide yes)
			(effects
				(font
					(size 1.27 1.27)
				)
			)
		)
		(property "Value" ""
			(at 0 0 0)
			(layer "F.Fab")
			(effects
				(font
					(size 1.27 1.27)
				)
			)
		)
		(duplicate_pad_numbers_are_jumpers no)
	)
	(footprint ""
		(layer "F.Cu")
		(at 147.32 -26.6192)
		(property "Reference" "TP22"
			(at -1.7272 -0.77343 0)
			(unlocked yes)
			(layer "F.SilkS")
			(effects
				(font
					(size 0.7874 0.5842)
					(thickness 0.1524)
				)
				(justify left)
			)
		)
		(property "Value" ""
			(at 0 0 0)
			(layer "F.Fab")
			(effects
				(font
					(size 1.27 1.27)
				)
			)
		)
		(property "Device Type" "TP_PIONT-TP010CT020B030_PTH-TPA"
			(at -1.341882 0.996696 0)
			(unlocked yes)
			(layer "F.Fab")
			(hide yes)
			(effects
				(font
					(size 0.7874 0.5842)
					(thickness 0.000001)
				)
				(justify left)
			)
		)
		(duplicate_pad_numbers_are_jumpers no)
		(fp_poly
			(pts
				(arc
					(start 0.889 0)
					(mid -0.889 0)
					(end 0.889 0)
				)
			)
			(stroke
				(width 0)
				(type default)
			)
			(fill no)
			(layer "B.CrtYd")
		)
		(fp_poly
			(pts
				(arc
					(start 0.889 0)
					(mid -0.889 0)
					(end 0.889 0)
				)
			)
			(stroke
				(width 0)
				(type default)
			)
			(fill no)
			(layer "F.CrtYd")
		)
		(pad "1" thru_hole circle
			(at 0 0)
			(size 0.508 0.508)
			(drill 0.254)
			(layers "*.Cu" "*.Mask")
			(remove_unused_layers no)
			(net "FPGA_IN_LM75B_INT3_N")
			(clearance 0.1016)
			(padstack
				(mode front_inner_back)
				(layer "Inner"
					(shape circle)
					(size 0.508 0.508)
					(clearance 0.1016)
				)
				(layer "B.Cu"
					(shape circle)
					(size 0.762 0.762)
					(clearance -0.0254)
				)
			)
		)
	)
	(footprint ""
		(layer "F.Cu")
		(at 97.282 -59.055 90)
		(property "Reference" "TP180"
			(at -2.9718 0.41275 90)
			(unlocked yes)
			(layer "F.SilkS")
			(effects
				(font
					(size 0.635 0.4064)
					(thickness 0.1524)
				)
				(justify left)
			)
		)
		(property "Value" ""
			(at 0 0 90)
			(layer "F.Fab")
			(effects
				(font
					(size 1.27 1.27)
				)
			)
		)
		(property "Device Type" "TP_PIONT-TP010CT020B030_PTH-TPA"
			(at -1.341882 0.996696 90)
			(unlocked yes)
			(layer "F.Fab")
			(hide yes)
			(effects
				(font
					(size 0.7874 0.5842)
					(thickness 0.1524)
				)
				(justify left)
			)
		)
		(duplicate_pad_numbers_are_jumpers no)
		(fp_poly
			(pts
				(arc
					(start 0 0.889)
					(mid 0 -0.889)
					(end 0 0.889)
				)
			)
			(stroke
				(width 0)
				(type default)
			)
			(fill no)
			(layer "B.CrtYd")
		)
		(fp_poly
			(pts
				(arc
					(start 0 0.889)
					(mid 0 -0.889)
					(end 0 0.889)
				)
			)
			(stroke
				(width 0)
				(type default)
			)
			(fill no)
			(layer "F.CrtYd")
		)
		(pad "1" thru_hole circle
			(at 0 0 90)
			(size 0.508 0.508)
			(drill 0.254)
			(layers "*.Cu" "*.Mask")
			(remove_unused_layers no)
			(net "IO_L20N_16")
			(clearance 0.1016)
			(padstack
				(mode front_inner_back)
				(layer "Inner"
					(shape circle)
					(size 0.508 0.508)
					(clearance 0.1016)
				)
				(layer "B.Cu"
					(shape circle)
					(size 0.762 0.762)
					(clearance -0.0254)
				)
			)
		)
	)
)
